(kicad_pcb
	(version 20260206)
	(generator "pcbnew")
	(generator_version "10.0")
	(general
		(thickness 1.6)
		(legacy_teardrops no)
	)
	(paper "A4")
	(title_block
		(title "v1-tray-backplane — T6M_tray_BP_c_1023_1120.brd")
		(comment 1 "Open CloudServer (Microsoft) / footprints 91-91 of 170")
	)
	(layers
		(0 "F.Cu" signal "TOP")
		(4 "In1.Cu" signal "GND")
		(6 "In2.Cu" signal "IN1")
		(8 "In3.Cu" signal "VCC")
		(10 "In4.Cu" signal "VCC1")
		(12 "In5.Cu" signal "IN2")
		(14 "In6.Cu" signal "GND1")
		(2 "B.Cu" signal "BOTTOM")
		(9 "F.Adhes" user "F.Adhesive")
		(11 "B.Adhes" user "B.Adhesive")
		(13 "F.Paste" user "Package Geometry/Pastemask Top")
		(15 "B.Paste" user "Package Geometry/Pastemask Bottom")
		(5 "F.SilkS" user "Ref Des/Silkscreen Top")
		(7 "B.SilkS" user "Ref Des/Silkscreen Bottom")
		(1 "F.Mask" user "Board Geometry/Soldermask Top")
		(3 "B.Mask" user "Board Geometry/Soldermask Bottom")
		(17 "Dwgs.User" user "User.Drawings")
		(19 "Cmts.User" user "User.Comments")
		(21 "Eco1.User" user "User.Eco1")
		(23 "Eco2.User" user "User.Eco2")
		(25 "Edge.Cuts" user "Board Geometry/Outline")
		(27 "Margin" user)
		(31 "F.CrtYd" user "Package Geometry/Place Bound Top")
		(29 "B.CrtYd" user "Package Geometry/Place Bound Bottom")
		(35 "F.Fab" user "Ref Des/Assembly Top")
		(33 "B.Fab" user "Ref Des/Assembly Bottom")
	)
	(footprint ""
		(layer "F.Cu")
		(at 104.8512 -2.9464 90)
		(property "Reference" "C19"
			(at -2.3876 -4.841748 90)
			(unlocked yes)
			(layer "F.SilkS")
			(effects
				(font
					(size 0.7874 0.5842)
					(thickness 0.1524)
				)
				(justify left)
			)
		)
		(property "Value" ""
			(at 0 0 90)
			(layer "F.Fab")
			(effects
				(font
					(size 1.27 1.27)
				)
			)
		)
		(duplicate_pad_numbers_are_jumpers no)
		(fp_line
			(start 0.7874 -0.4064)
			(end 0.7874 0.4064)
			(stroke
				(width 0.1524)
				(type default)
			)
			(layer "F.SilkS")
		)
		(fp_line
			(start -0.7874 -0.4064)
			(end 0.7874 -0.4064)
			(stroke
				(width 0.1524)
				(type default)
			)
			(layer "F.SilkS")
		)
		(fp_line
			(start 0 0.381)
			(end 0 -0.381)
			(stroke
				(width 0.1524)
				(type default)
			)
			(layer "F.SilkS")
		)
		(fp_line
			(start 0.7874 0.4064)
			(end -0.7874 0.4064)
			(stroke
				(width 0.1524)
				(type default)
			)
			(layer "F.SilkS")
		)
		(fp_line
			(start -0.7874 0.4064)
			(end -0.7874 -0.4064)
			(stroke
				(width 0.1524)
				(type default)
			)
			(layer "F.SilkS")
		)
		(fp_poly
			(pts
				(xy -0.5334 0.254) (xy -0.635 0.254) (xy -0.635 0.2286) (xy -0.635 -0.254) (xy -0.5334 -0.254) (xy -0.5334 -0.2794)
				(xy 0.5334 -0.2794) (xy 0.5334 -0.254) (xy 0.635 -0.254) (xy 0.635 0.254) (xy 0.5334 0.254) (xy 0.5334 0.2794)
				(xy -0.508 0.2794) (xy -0.5334 0.2794)
			)
			(stroke
				(width 0)
				(type default)
			)
			(fill no)
			(layer "F.CrtYd")
		)
		(pad "1" smd rect
			(at 0.40005 0 90)
			(size 0.4572 0.508)
			(layers "F.Cu" "F.Mask" "F.Paste")
			(net "P3V3_10G_2_VCCT")
		)
		(pad "2" smd rect
			(at -0.40005 0 90)
			(size 0.4572 0.508)
			(layers "F.Cu" "F.Mask" "F.Paste")
			(net "GND")
		)
	)
)
